(kicad_pcb
	(version 20260206)
	(generator "pcbnew")
	(generator_version "10.0")
	(general
		(thickness 1.6)
		(legacy_teardrops no)
	)
	(paper "A4")
	(title_block
		(title "01162023_DA0F0TEBIF0_F0T_Expander_BD_F_brd_V02_OCP.brd")
		(comment 1 "Grand Teton / footprints 536-541 of 9728")
	)
	(layers
		(0 "F.Cu" signal "TOP")
		(4 "In1.Cu" signal "GND")
		(6 "In2.Cu" signal "VCC")
		(8 "In3.Cu" signal "VCC1")
		(10 "In4.Cu" signal "GND1")
		(12 "In5.Cu" signal "IN1")
		(14 "In6.Cu" signal "GND2")
		(16 "In7.Cu" signal "IN2")
		(18 "In8.Cu" signal "GND3")
		(20 "In9.Cu" signal "IN3")
		(22 "In10.Cu" signal "GND4")
		(24 "In11.Cu" signal "IN4")
		(26 "In12.Cu" signal "GND5")
		(28 "In13.Cu" signal "IN5")
		(30 "In14.Cu" signal "GND6")
		(32 "In15.Cu" signal "IN6")
		(34 "In16.Cu" signal "GND7")
		(2 "B.Cu" signal "BOTTOM")
		(9 "F.Adhes" user "F.Adhesive")
		(11 "B.Adhes" user "B.Adhesive")
		(13 "F.Paste" user "Package Geometry/Pastemask Top")
		(15 "B.Paste" user "Package Geometry/Pastemask Bottom")
		(5 "F.SilkS" user "Ref Des/Silkscreen Top")
		(7 "B.SilkS" user "Ref Des/Silkscreen Bottom")
		(1 "F.Mask" user "Board Geometry/Soldermask Top")
		(3 "B.Mask" user "Board Geometry/Soldermask Bottom")
		(17 "Dwgs.User" user "User.Drawings")
		(19 "Cmts.User" user "User.Comments")
		(21 "Eco1.User" user "User.Eco1")
		(23 "Eco2.User" user "User.Eco2")
		(25 "Edge.Cuts" user "Board Geometry/Outline")
		(27 "Margin" user)
		(31 "F.CrtYd" user "Package Geometry/Place Bound Top")
		(29 "B.CrtYd" user "Package Geometry/Place Bound Bottom")
		(35 "F.Fab" user "Ref Des/Assembly Top")
		(33 "B.Fab" user "Ref Des/Assembly Bottom")
	)
	(footprint ""
		(layer "F.Cu")
		(at 52.243736 -43.85691)
		(property "Reference" "R521"
			(at 0 0 0)
			(layer "F.SilkS")
			(hide yes)
			(effects
				(font
					(size 1.27 1.27)
				)
			)
		)
		(property "Value" ""
			(at 0 0 0)
			(layer "F.Fab")
			(effects
				(font
					(size 1.27 1.27)
				)
			)
		)
		(duplicate_pad_numbers_are_jumpers no)
		(fp_line
			(start -0.7874 -0.4064)
			(end 0.7874 -0.4064)
			(stroke
				(width 0.1524)
				(type default)
			)
			(layer "F.SilkS")
		)
		(fp_line
			(start -0.7874 0.4064)
			(end -0.7874 -0.4064)
			(stroke
				(width 0.1524)
				(type default)
			)
			(layer "F.SilkS")
		)
		(fp_line
			(start 0.7874 -0.4064)
			(end 0.7874 0.4064)
			(stroke
				(width 0.1524)
				(type default)
			)
			(layer "F.SilkS")
		)
		(fp_line
			(start 0.7874 0.4064)
			(end -0.7874 0.4064)
			(stroke
				(width 0.1524)
				(type default)
			)
			(layer "F.SilkS")
		)
		(fp_line
			(start -0.67945 -0.305054)
			(end -0.12065 -0.305054)
			(stroke
				(width 0.1)
				(type default)
			)
			(layer "F.Fab")
		)
		(fp_line
			(start -0.67945 0.3048)
			(end -0.67945 -0.305054)
			(stroke
				(width 0.1)
				(type default)
			)
			(layer "F.Fab")
		)
		(fp_line
			(start -0.12065 -0.305054)
			(end -0.12065 -0.2794)
			(stroke
				(width 0.1)
				(type default)
			)
			(layer "F.Fab")
		)
		(fp_line
			(start -0.12065 -0.2794)
			(end 0.12065 -0.2794)
			(stroke
				(width 0.1)
				(type default)
			)
			(layer "F.Fab")
		)
		(fp_line
			(start -0.12065 0.2794)
			(end -0.12065 0.3048)
			(stroke
				(width 0.1)
				(type default)
			)
			(layer "F.Fab")
		)
		(fp_line
			(start -0.12065 0.3048)
			(end -0.67945 0.3048)
			(stroke
				(width 0.1)
				(type default)
			)
			(layer "F.Fab")
		)
		(fp_line
			(start 0.120396 0.2794)
			(end -0.12065 0.2794)
			(stroke
				(width 0.1)
				(type default)
			)
			(layer "F.Fab")
		)
		(fp_line
			(start 0.120396 0.3048)
			(end 0.120396 0.2794)
			(stroke
				(width 0.1)
				(type default)
			)
			(layer "F.Fab")
		)
		(fp_line
			(start 0.12065 -0.3048)
			(end 0.67945 -0.3048)
			(stroke
				(width 0.1)
				(type default)
			)
			(layer "F.Fab")
		)
		(fp_line
			(start 0.12065 -0.2794)
			(end 0.12065 -0.3048)
			(stroke
				(width 0.1)
				(type default)
			)
			(layer "F.Fab")
		)
		(fp_line
			(start 0.67945 -0.3048)
			(end 0.67945 0.3048)
			(stroke
				(width 0.1)
				(type default)
			)
			(layer "F.Fab")
		)
		(fp_line
			(start 0.67945 0.3048)
			(end 0.120396 0.3048)
			(stroke
				(width 0.1)
				(type default)
			)
			(layer "F.Fab")
		)
		(pad "1" smd circle
			(at -0.40005 0)
			(size 0 0)
			(layers "F.Cu" "F.Mask" "F.Paste")
			(net "SSD1_ADC_A1")
		)
		(pad "2" smd circle
			(at 0.40005 0)
			(size 0 0)
			(layers "F.Cu" "F.Mask" "F.Paste")
			(net "GND")
		)
	)
	(footprint ""
		(layer "F.Cu")
		(at 442.553344 18.028412 180)
		(property "Reference" "DE05F_1"
			(at 2.828544 3.218942 0)
			(unlocked yes)
			(layer "F.SilkS")
			(effects
				(font
					(size 0.7874 0.5842)
					(thickness 0.1524)
				)
				(justify left)
			)
		)
		(property "Value" ""
			(at 0 0 180)
			(layer "F.Fab")
			(effects
				(font
					(size 1.27 1.27)
				)
			)
		)
		(duplicate_pad_numbers_are_jumpers no)
		(fp_line
			(start 1.2192 2.1082)
			(end -1.2192 2.1082)
			(stroke
				(width 0.1524)
				(type default)
			)
			(layer "F.SilkS")
		)
		(fp_line
			(start 1.2192 -2.1082)
			(end 1.2192 2.1082)
			(stroke
				(width 0.1524)
				(type default)
			)
			(layer "F.SilkS")
		)
		(fp_line
			(start -1.2192 2.1082)
			(end -1.2192 -2.1082)
			(stroke
				(width 0.1524)
				(type default)
			)
			(layer "F.SilkS")
		)
		(fp_line
			(start -1.2192 -2.1082)
			(end 1.2192 -2.1082)
			(stroke
				(width 0.1524)
				(type default)
			)
			(layer "F.SilkS")
		)
		(pad "" np_thru_hole circle
			(at -2.8829 -1.27 90)
			(size 1.0414 1.0414)
			(drill 1.0414)
			(layers "*.Cu" "*.Mask")
			(clearance 0.381)
			(thermal_gap 0.381)
		)
		(pad "" np_thru_hole circle
			(at -2.8829 1.27 90)
			(size 1.0414 1.0414)
			(drill 1.0414)
			(layers "*.Cu" "*.Mask")
			(clearance 0.381)
			(thermal_gap 0.381)
		)
		(pad "" np_thru_hole circle
			(at 3.4671 -1.27 90)
			(size 1.0414 1.0414)
			(drill 1.0414)
			(layers "*.Cu" "*.Mask")
			(clearance 0.381)
			(thermal_gap 0.381)
		)
		(pad "" np_thru_hole circle
			(at 3.4671 1.27 90)
			(size 1.0414 1.0414)
			(drill 1.0414)
			(layers "*.Cu" "*.Mask")
			(clearance 0.381)
			(thermal_gap 0.381)
		)
		(pad "1" smd rect
			(at 0.8255 -0.249936 90)
			(size 0.3048 0.508)
			(layers "F.Cu" "F.Mask" "F.Paste")
			(net "85_5INCH_IN3_DP")
		)
		(pad "2" smd rect
			(at 0.8255 0.249936 90)
			(size 0.3048 0.508)
			(layers "F.Cu" "F.Mask" "F.Paste")
			(net "85_5INCH_IN3_DN")
		)
		(pad "3" smd circle
			(at 0 0 180)
			(size 0 0)
			(layers "F.Cu" "F.Mask" "F.Paste")
			(net "COUPON_GND2")
		)
		(zone
			(layer "F.Cu")
			(hatch none 0.5)
			(connect_pads
				(clearance 0)
			)
			(min_thickness 0.25)
			(keepout
				(tracks not_allowed)
				(vias allowed)
				(pads allowed)
				(copperpour not_allowed)
				(footprints allowed)
			)
			(placement
				(enabled no)
				(sheetname "")
			)
			(fill
				(thermal_gap 0.5)
				(thermal_bridge_width 0.5)
				(island_removal_mode 0)
			)
			(polygon
				(pts
					(xy 441.435744 18.577052) (xy 441.435744 18.481548) (xy 442.032644 18.481548) (xy 442.032644 18.075148)
					(xy 441.435744 18.075148) (xy 441.435744 17.981676) (xy 442.032644 17.981676) (xy 442.032644 17.575276)
					(xy 441.435744 17.575276) (xy 441.435744 17.479772) (xy 442.134244 17.479772) (xy 442.134244 18.577052)
				)
			)
		)
		(zone
			(layers "F.Cu" "B.Cu" "In1.Cu" "In2.Cu" "In3.Cu" "In4.Cu" "In5.Cu" "In6.Cu"
				"In7.Cu" "In8.Cu" "In9.Cu" "In10.Cu" "In11.Cu" "In12.Cu" "In13.Cu" "In14.Cu"
				"In15.Cu" "In16.Cu"
			)
			(hatch none 0.5)
			(connect_pads
				(clearance 0)
			)
			(min_thickness 0.25)
			(keepout
				(tracks not_allowed)
				(vias allowed)
				(pads allowed)
				(copperpour not_allowed)
				(footprints allowed)
			)
			(placement
				(enabled no)
				(sheetname "")
			)
			(fill
				(thermal_gap 0.5)
				(thermal_bridge_width 0.5)
				(island_removal_mode 0)
			)
			(polygon
				(pts
					(arc
						(start 440.013344 16.758412)
						(mid 438.159144 16.758412)
						(end 440.013344 16.758412)
					)
				)
			)
		)
		(zone
			(layers "F.Cu" "B.Cu" "In1.Cu" "In2.Cu" "In3.Cu" "In4.Cu" "In5.Cu" "In6.Cu"
				"In7.Cu" "In8.Cu" "In9.Cu" "In10.Cu" "In11.Cu" "In12.Cu" "In13.Cu" "In14.Cu"
				"In15.Cu" "In16.Cu"
			)
			(hatch none 0.5)
			(connect_pads
				(clearance 0)
			)
			(min_thickness 0.25)
			(keepout
				(tracks not_allowed)
				(vias allowed)
				(pads allowed)
				(copperpour not_allowed)
				(footprints allowed)
			)
			(placement
				(enabled no)
				(sheetname "")
			)
			(fill
				(thermal_gap 0.5)
				(thermal_bridge_width 0.5)
				(island_removal_mode 0)
			)
			(polygon
				(pts
					(arc
						(start 440.013344 19.298412)
						(mid 438.159144 19.298412)
						(end 440.013344 19.298412)
					)
				)
			)
		)
		(zone
			(layers "F.Cu" "B.Cu" "In1.Cu" "In2.Cu" "In3.Cu" "In4.Cu" "In5.Cu" "In6.Cu"
				"In7.Cu" "In8.Cu" "In9.Cu" "In10.Cu" "In11.Cu" "In12.Cu" "In13.Cu" "In14.Cu"
				"In15.Cu" "In16.Cu"
			)
			(hatch none 0.5)
			(connect_pads
				(clearance 0)
			)
			(min_thickness 0.25)
			(keepout
				(tracks not_allowed)
				(vias allowed)
				(pads allowed)
				(copperpour not_allowed)
				(footprints allowed)
			)
			(placement
				(enabled no)
				(sheetname "")
			)
			(fill
				(thermal_gap 0.5)
				(thermal_bridge_width 0.5)
				(island_removal_mode 0)
			)
			(polygon
				(pts
					(arc
						(start 446.363344 16.758412)
						(mid 444.509144 16.758412)
						(end 446.363344 16.758412)
					)
				)
			)
		)
		(zone
			(layers "F.Cu" "B.Cu" "In1.Cu" "In2.Cu" "In3.Cu" "In4.Cu" "In5.Cu" "In6.Cu"
				"In7.Cu" "In8.Cu" "In9.Cu" "In10.Cu" "In11.Cu" "In12.Cu" "In13.Cu" "In14.Cu"
				"In15.Cu" "In16.Cu"
			)
			(hatch none 0.5)
			(connect_pads
				(clearance 0)
			)
			(min_thickness 0.25)
			(keepout
				(tracks not_allowed)
				(vias allowed)
				(pads allowed)
				(copperpour not_allowed)
				(footprints allowed)
			)
			(placement
				(enabled no)
				(sheetname "")
			)
			(fill
				(thermal_gap 0.5)
				(thermal_bridge_width 0.5)
				(island_removal_mode 0)
			)
			(polygon
				(pts
					(arc
						(start 446.363344 19.298412)
						(mid 444.509144 19.298412)
						(end 446.363344 19.298412)
					)
				)
			)
		)
	)
	(footprint ""
		(layer "F.Cu")
		(at 259.399786 -334.015588 90)
		(property "Reference" "C4485"
			(at 0 0 90)
			(layer "F.SilkS")
			(hide yes)
			(effects
				(font
					(size 1.27 1.27)
				)
			)
		)
		(property "Value" ""
			(at 0 0 90)
			(layer "F.Fab")
			(effects
				(font
					(size 1.27 1.27)
				)
			)
		)
		(duplicate_pad_numbers_are_jumpers no)
		(fp_line
			(start 0.7874 -0.4064)
			(end 0.7874 0.4064)
			(stroke
				(width 0.1524)
				(type default)
			)
			(layer "F.SilkS")
		)
		(fp_line
			(start -0.7874 -0.4064)
			(end 0.7874 -0.4064)
			(stroke
				(width 0.1524)
				(type default)
			)
			(layer "F.SilkS")
		)
		(fp_line
			(start 0.7874 0.4064)
			(end -0.7874 0.4064)
			(stroke
				(width 0.1524)
				(type default)
			)
			(layer "F.SilkS")
		)
		(fp_line
			(start -0.7874 0.4064)
			(end -0.7874 -0.4064)
			(stroke
				(width 0.1524)
				(type default)
			)
			(layer "F.SilkS")
		)
		(fp_line
			(start -0.12065 -0.305054)
			(end -0.12065 -0.2794)
			(stroke
				(width 0.1)
				(type default)
			)
			(layer "F.Fab")
		)
		(fp_line
			(start -0.67945 -0.305054)
			(end -0.12065 -0.305054)
			(stroke
				(width 0.1)
				(type default)
			)
			(layer "F.Fab")
		)
		(fp_line
			(start 0.67945 -0.3048)
			(end 0.67945 0.3048)
			(stroke
				(width 0.1)
				(type default)
			)
			(layer "F.Fab")
		)
		(fp_line
			(start 0.12065 -0.3048)
			(end 0.67945 -0.3048)
			(stroke
				(width 0.1)
				(type default)
			)
			(layer "F.Fab")
		)
		(fp_line
			(start 0.12065 -0.2794)
			(end 0.12065 -0.3048)
			(stroke
				(width 0.1)
				(type default)
			)
			(layer "F.Fab")
		)
		(fp_line
			(start -0.12065 -0.2794)
			(end 0.12065 -0.2794)
			(stroke
				(width 0.1)
				(type default)
			)
			(layer "F.Fab")
		)
		(fp_line
			(start 0.120396 0.2794)
			(end -0.12065 0.2794)
			(stroke
				(width 0.1)
				(type default)
			)
			(layer "F.Fab")
		)
		(fp_line
			(start -0.12065 0.2794)
			(end -0.12065 0.3048)
			(stroke
				(width 0.1)
				(type default)
			)
			(layer "F.Fab")
		)
		(fp_line
			(start 0.67945 0.3048)
			(end 0.120396 0.3048)
			(stroke
				(width 0.1)
				(type default)
			)
			(layer "F.Fab")
		)
		(fp_line
			(start 0.120396 0.3048)
			(end 0.120396 0.2794)
			(stroke
				(width 0.1)
				(type default)
			)
			(layer "F.Fab")
		)
		(fp_line
			(start -0.12065 0.3048)
			(end -0.67945 0.3048)
			(stroke
				(width 0.1)
				(type default)
			)
			(layer "F.Fab")
		)
		(fp_line
			(start -0.67945 0.3048)
			(end -0.67945 -0.305054)
			(stroke
				(width 0.1)
				(type default)
			)
			(layer "F.Fab")
		)
		(pad "1" smd circle
			(at -0.40005 0 90)
			(size 0 0)
			(layers "F.Cu" "F.Mask" "F.Paste")
			(net "HSC_OC_VOL")
		)
		(pad "2" smd circle
			(at 0.40005 0 90)
			(size 0 0)
			(layers "F.Cu" "F.Mask" "F.Paste")
			(net "GND")
		)
	)
	(footprint ""
		(layer "F.Cu")
		(at 267.569442 -260.088634 -90)
		(property "Reference" "R4581"
			(at 0 0 270)
			(layer "F.SilkS")
			(hide yes)
			(effects
				(font
					(size 1.27 1.27)
				)
			)
		)
		(property "Value" ""
			(at 0 0 270)
			(layer "F.Fab")
			(effects
				(font
					(size 1.27 1.27)
				)
			)
		)
		(duplicate_pad_numbers_are_jumpers no)
		(fp_line
			(start -0.7874 0.4064)
			(end -0.7874 -0.4064)
			(stroke
				(width 0.1524)
				(type default)
			)
			(layer "F.SilkS")
		)
		(fp_line
			(start 0.7874 0.4064)
			(end -0.7874 0.4064)
			(stroke
				(width 0.1524)
				(type default)
			)
			(layer "F.SilkS")
		)
		(fp_line
			(start -0.7874 -0.4064)
			(end 0.7874 -0.4064)
			(stroke
				(width 0.1524)
				(type default)
			)
			(layer "F.SilkS")
		)
		(fp_line
			(start 0.7874 -0.4064)
			(end 0.7874 0.4064)
			(stroke
				(width 0.1524)
				(type default)
			)
			(layer "F.SilkS")
		)
		(fp_line
			(start -0.67945 0.3048)
			(end -0.67945 -0.305054)
			(stroke
				(width 0.1)
				(type default)
			)
			(layer "F.Fab")
		)
		(fp_line
			(start -0.12065 0.3048)
			(end -0.67945 0.3048)
			(stroke
				(width 0.1)
				(type default)
			)
			(layer "F.Fab")
		)
		(fp_line
			(start 0.120396 0.3048)
			(end 0.120396 0.2794)
			(stroke
				(width 0.1)
				(type default)
			)
			(layer "F.Fab")
		)
		(fp_line
			(start 0.67945 0.3048)
			(end 0.120396 0.3048)
			(stroke
				(width 0.1)
				(type default)
			)
			(layer "F.Fab")
		)
		(fp_line
			(start -0.12065 0.2794)
			(end -0.12065 0.3048)
			(stroke
				(width 0.1)
				(type default)
			)
			(layer "F.Fab")
		)
		(fp_line
			(start 0.120396 0.2794)
			(end -0.12065 0.2794)
			(stroke
				(width 0.1)
				(type default)
			)
			(layer "F.Fab")
		)
		(fp_line
			(start -0.12065 -0.2794)
			(end 0.12065 -0.2794)
			(stroke
				(width 0.1)
				(type default)
			)
			(layer "F.Fab")
		)
		(fp_line
			(start 0.12065 -0.2794)
			(end 0.12065 -0.3048)
			(stroke
				(width 0.1)
				(type default)
			)
			(layer "F.Fab")
		)
		(fp_line
			(start 0.12065 -0.3048)
			(end 0.67945 -0.3048)
			(stroke
				(width 0.1)
				(type default)
			)
			(layer "F.Fab")
		)
		(fp_line
			(start 0.67945 -0.3048)
			(end 0.67945 0.3048)
			(stroke
				(width 0.1)
				(type default)
			)
			(layer "F.Fab")
		)
		(fp_line
			(start -0.67945 -0.305054)
			(end -0.12065 -0.305054)
			(stroke
				(width 0.1)
				(type default)
			)
			(layer "F.Fab")
		)
		(fp_line
			(start -0.12065 -0.305054)
			(end -0.12065 -0.2794)
			(stroke
				(width 0.1)
				(type default)
			)
			(layer "F.Fab")
		)
		(pad "1" smd circle
			(at -0.40005 0 270)
			(size 0 0)
			(layers "F.Cu" "F.Mask" "F.Paste")
			(net "PCEPLL3_VDDA18_PEX2")
		)
		(pad "2" smd circle
			(at 0.40005 0 270)
			(size 0 0)
			(layers "F.Cu" "F.Mask" "F.Paste")
			(net "PCEPLL3_VDDA18_PEX2_R")
		)
	)
	(footprint ""
		(layer "F.Cu")
		(at 338.263484 -350.098614 90)
		(property "Reference" "C526"
			(at 0 0 90)
			(layer "F.SilkS")
			(hide yes)
			(effects
				(font
					(size 1.27 1.27)
				)
			)
		)
		(property "Value" ""
			(at 0 0 90)
			(layer "F.Fab")
			(effects
				(font
					(size 1.27 1.27)
				)
			)
		)
		(duplicate_pad_numbers_are_jumpers no)
		(fp_line
			(start 0.299974 -0.150114)
			(end 0.299974 0.150114)
			(stroke
				(width 0.1)
				(type default)
			)
			(layer "F.Fab")
		)
		(fp_line
			(start -0.299974 -0.150114)
			(end 0.299974 -0.150114)
			(stroke
				(width 0.1)
				(type default)
			)
			(layer "F.Fab")
		)
		(fp_line
			(start 0.299974 0.150114)
			(end -0.299974 0.150114)
			(stroke
				(width 0.1)
				(type default)
			)
			(layer "F.Fab")
		)
		(fp_line
			(start -0.299974 0.150114)
			(end -0.299974 -0.150114)
			(stroke
				(width 0.1)
				(type default)
			)
			(layer "F.Fab")
		)
		(pad "1" smd rect
			(at -0.2667 0 90)
			(size 0.3048 0.381)
			(layers "F.Cu" "F.Mask" "F.Paste")
			(net "P5E_PEX2_STN5_TX_DN<92>")
		)
		(pad "2" smd rect
			(at 0.2667 0 90)
			(size 0.3048 0.381)
			(layers "F.Cu" "F.Mask" "F.Paste")
			(net "P5E_PEX2_STN5_TX_C_DN<92>")
		)
	)
	(footprint ""
		(layer "F.Cu")
		(at 74.820526 -70.307454 90)
		(property "Reference" "PC648"
			(at 0 0 90)
			(layer "F.SilkS")
			(hide yes)
			(effects
				(font
					(size 1.27 1.27)
				)
			)
		)
		(property "Value" ""
			(at 0 0 90)
			(layer "F.Fab")
			(effects
				(font
					(size 1.27 1.27)
				)
			)
		)
		(duplicate_pad_numbers_are_jumpers no)
		(fp_line
			(start 0.7874 -0.4064)
			(end 0.7874 0.4064)
			(stroke
				(width 0.1524)
				(type default)
			)
			(layer "F.SilkS")
		)
		(fp_line
			(start -0.7874 -0.4064)
			(end 0.7874 -0.4064)
			(stroke
				(width 0.1524)
				(type default)
			)
			(layer "F.SilkS")
		)
		(fp_line
			(start 0.7874 0.4064)
			(end -0.7874 0.4064)
			(stroke
				(width 0.1524)
				(type default)
			)
			(layer "F.SilkS")
		)
		(fp_line
			(start -0.7874 0.4064)
			(end -0.7874 -0.4064)
			(stroke
				(width 0.1524)
				(type default)
			)
			(layer "F.SilkS")
		)
		(fp_line
			(start -0.12065 -0.305054)
			(end -0.12065 -0.2794)
			(stroke
				(width 0.1)
				(type default)
			)
			(layer "F.Fab")
		)
		(fp_line
			(start -0.67945 -0.305054)
			(end -0.12065 -0.305054)
			(stroke
				(width 0.1)
				(type default)
			)
			(layer "F.Fab")
		)
		(fp_line
			(start 0.67945 -0.3048)
			(end 0.67945 0.3048)
			(stroke
				(width 0.1)
				(type default)
			)
			(layer "F.Fab")
		)
		(fp_line
			(start 0.12065 -0.3048)
			(end 0.67945 -0.3048)
			(stroke
				(width 0.1)
				(type default)
			)
			(layer "F.Fab")
		)
		(fp_line
			(start 0.12065 -0.2794)
			(end 0.12065 -0.3048)
			(stroke
				(width 0.1)
				(type default)
			)
			(layer "F.Fab")
		)
		(fp_line
			(start -0.12065 -0.2794)
			(end 0.12065 -0.2794)
			(stroke
				(width 0.1)
				(type default)
			)
			(layer "F.Fab")
		)
		(fp_line
			(start 0.120396 0.2794)
			(end -0.12065 0.2794)
			(stroke
				(width 0.1)
				(type default)
			)
			(layer "F.Fab")
		)
		(fp_line
			(start -0.12065 0.2794)
			(end -0.12065 0.3048)
			(stroke
				(width 0.1)
				(type default)
			)
			(layer "F.Fab")
		)
		(fp_line
			(start 0.67945 0.3048)
			(end 0.120396 0.3048)
			(stroke
				(width 0.1)
				(type default)
			)
			(layer "F.Fab")
		)
		(fp_line
			(start 0.120396 0.3048)
			(end 0.120396 0.2794)
			(stroke
				(width 0.1)
				(type default)
			)
			(layer "F.Fab")
		)
		(fp_line
			(start -0.12065 0.3048)
			(end -0.67945 0.3048)
			(stroke
				(width 0.1)
				(type default)
			)
			(layer "F.Fab")
		)
		(fp_line
			(start -0.67945 0.3048)
			(end -0.67945 -0.305054)
			(stroke
				(width 0.1)
				(type default)
			)
			(layer "F.Fab")
		)
		(pad "1" smd circle
			(at -0.40005 0 90)
			(size 0 0)
			(layers "F.Cu" "F.Mask" "F.Paste")
			(net "P12V_AUX")
		)
		(pad "2" smd circle
			(at 0.40005 0 90)
			(size 0 0)
			(layers "F.Cu" "F.Mask" "F.Paste")
			(net "GND")
		)
	)
)
